FILE_TYPE = CONNECTIVITY;
{Allegro Design Entry HDL 16.6-p007 (v16-6-112F) 10/10/2012}
"PAGE_NUMBER" = 122;
0"NC";
1"P1V8_PCH_STBY\g";
2"P1V05_PCH_STBY\g";
3"P3V3_STBY\g";
4"P1V05_PCH_STBY_WM26_PLL\g";
5"P1V05_PCH_STBY_WM20_PLL\g";
6"P1V05_PCH_STBY_KR_PLL\g";
7"P1V05_PCH_STBY_ISCLK_PLL\g";
8"P1V05_PCH_STBY_VCCA_XTAL\g";
9"P3V3_RTC_STBY\g";
10"P1V05_PCH_STBY\g";
11"P1V05_PCH_STBY_VCCA_PLL0\g";
12"P1V05_PCH_STBY_VCCA_PLL1\g";
13"TP_PCH_RSVD30";
14"TP_PCH_RSVD28";
15"TP_PCH_RSVD29";
16"TP_PCH_RSVD31";
17"TP_PCH_RSVD58";
18"TP_PCH_RSVD59";
19"A_PVCCRTC_EXT_CAP";
%"P1V8_PCH_STBY"
"1","(-1450,4925)","2","mstr_symbols","I21";
;
VOLTAGE"1.8V"
CDS_LIB"mstr_symbols"
BODY_TYPE"PLUMBING"
HDL_POWER"P1V8_PCH_STBY";
"G\NAC"1;
%"P1V05_PCH_STBY"
"1","(-5650,5225)","0","mstr_symbols","I24";
;
VOLTAGE"1.05V"
CDS_LIB"mstr_symbols"
BODY_TYPE"PLUMBING"
HDL_POWER"P1V05_PCH_STBY";
"G\NAC"2;
%"LBG_CORE_QAT_EXT_D"
"9","(-3900,3075)","0","mstr_u_proc","I63";
;
CDS_SEC"9"
LOCATION"U7C1"
PART_NUMBER"H91415-002"
MATERIAL"IC"
PACK_TYPE"BGA1"
CDS_LIB"mstr_u_proc"
BOM_COST"SB"
CDS_LOCATION"U7C1"
SEC"9"
SEC_TYPE"BGA1"
ROOM"SB";
"VCCPSPI"
$PN"AR24"3;
"VCCP_3P3<5>"
$PN"AN24"3;
"VCCPDSW_3P3"
$PN"AH24"3;
"VCCPUSBDSW_3P3"
$PN"BA48"3;
"VCCMPHY_1P05<12>"
$PN"AK43"2;
"VCCMPHY_1P05<10>"
$PN"AM43"2;
"VCCMPHY_1P05<9>"
$PN"AM45"2;
"VCCP_UPPLLUNF_1P05"
$PN"AM48"2;
"VCCP_UPPLL_1P05<0>"
$PN"AN50"5;
"VCCP_HSIOPLLUNF_1P05"
$PN"AT48"2;
"VCCP_HSIOPLL_1P05<2>"
$PN"AU48"4;
"VCCP_HSIOPLL_1P05<3>"
$PN"AP48"4;
"VCCA_PLL0_1P05"
$PN"AG48"11;
"VCCA_PLL1_1P05"
$PN"AE45"12;
"VCCPRIM_1P05<17>"
$PN"AK27"2;
"RSVD<59>"
$PN"AT27"18;
"RSVD<58>"
$PN"AP27"17;
"RSVD<31>"
$PN"P29"16;
"RSVD<30>"
$PN"R31"13;
"RSVD<29>"
$PN"P33"15;
"RSVD<28>"
$PN"R35"14;
"VCCA_CLKFILT_1P05<4>"
$PN"AE46"7;
"VCCA_CLKFILT_1P05<3>"
$PN"AJ48"7;
"VCCA_CLKFILT_1P05<2>"
$PN"AJ46"7;
"VCCA_CLKFILT_1P05<1>"
$PN"AG45"7;
"VCCA_CLKFILT_1P05<0>"
$PN"W50"7;
"VCCA_CLKUNF_1P05<1>"
$PN"U50"2;
"VCCA_CLKUNF_1P05<0>"
$PN"AH50"2;
"VCCA_CLKXTAL_1P05"
$PN"AD50"8;
"VCCMPHY_1P05<11>"
$PN"AK45"2;
"VCCMPHY_1P05<8>"
$PN"AP43"2;
"VCCMPHY_1P05<7>"
$PN"AP45"2;
"VCCMPHY_1P05<6>"
$PN"AT43"2;
"VCCMPHY_1P05<5>"
$PN"AT45"2;
"VCCMPHY_1P05<4>"
$PN"AU43"2;
"VCCMPHY_1P05<3>"
$PN"AU45"2;
"VCCMPHY_1P05<2>"
$PN"AJ43"2;
"VCCMPHY_1P05<1>"
$PN"AW43"2;
"VCCMPHY_1P05<0>"
$PN"AW45"2;
"VCCP10GBEPLL_1P05<3>"
$PN"BA39"6;
"VCCP10GBEPLL_1P05<2>"
$PN"BA41"6;
"VCCP10GBEPLL_1P05<1>"
$PN"BB40"6;
"VCCP10GBEPLL_1P05<0>"
$PN"BD38"6;
"VCCP10GBE_HV_1P8<1>"
$PN"BA27"1;
"VCCP10GBE_HV_1P8<0>"
$PN"BA29"1;
"VCCP10GBE_LV_1P05<6>"
$PN"BA30"2;
"VCCP10GBE_LV_1P05<5>"
$PN"BA32"2;
"VCCP10GBE_LV_1P05<4>"
$PN"BA34"2;
"VCCP10GBE_LV_1P05<3>"
$PN"BA36"2;
"VCCP10GBE_LV_1P05<2>"
$PN"BA37"2;
"VCCP10GBE_LV_1P05<1>"
$PN"BB33"2;
"VCCP10GBE_LV_1P05<0>"
$PN"BB37"2;
"VCCPGPPA"
$PN"AW24"3;
"VCCPGPPB"
$PN"BE26"3;
"VCCPGPPC"
$PN"BE40"3;
"VCCPGPPD"
$PN"BA43"3;
"VCCPGPPE"
$PN"BE44"3;
"VCCPGPPF"
$PN"AU27"3;
"VCCPGPPG"
$PN"BA26"3;
"VCCPGPPH"
$PN"BA24"3;
"VCCPGPPJ"
$PN"BB26"3;
"VCCPGPPK"
$PN"AU24"3;
"VCCPGPP_1P8<6>"
$PN"AK24"1;
"VCCPGPP_1P8<5>"
$PN"AW27"1;
"VCCPGPP_1P8<4>"
$PN"AP29"1;
"VCCPGPP_1P8<3>"
$PN"AM29"1;
"VCCPGPP_1P8<2>"
$PN"AT29"1;
"VCCPGPP_1P8<1>"
$PN"AW29"1;
"VCCPGPP_1P8<0>"
$PN"AU29"1;
"VCCPHDA_1P8"
$PN"AG27"1;
"VCCPRIM_1P05<19>"
$PN"Y26"10;
"VCCPRIM_1P05<18>"
$PN"AA24"10;
"VCCPRIM_1P05<16>"
$PN"R42"2;
"VCCPRIM_1P05<15>"
$PN"R46"2;
"VCCPRIM_1P05<14>"
$PN"T44"2;
"VCCPRIM_1P05<13>"
$PN"U46"2;
"VCCPRIM_1P05<12>"
$PN"V44"2;
"VCCPRIM_1P05<11>"
$PN"Y45"2;
"VCCPRIM_1P05<10>"
$PN"Y46"2;
"VCCPRIM_1P05<9>"
$PN"AA45"2;
"VCCPRIM_1P05<8>"
$PN"AA46"2;
"VCCPRIM_1P05<7>"
$PN"AC26"2;
"VCCPRIM_1P05<6>"
$PN"AJ29"2;
"VCCPRIM_1P05<5>"
$PN"AM27"2;
"VCCPRIM_1P05<4>"
$PN"AT39"2;
"VCCPRIM_1P05<3>"
$PN"AU37"2;
"VCCPRIM_1P05<2>"
$PN"AU39"2;
"VCCPRIM_1P05<1>"
$PN"BE48"2;
"VCCPRIM_1P05<0>"
$PN"BF46"2;
"VCCPRTC"
$PN"AJ27"9;
"VCCPRTCPRIM_3P3"
$PN"AG29"3;
"VCCPSPI_1P8"
$PN"AK29"1;
"VCCP_1P8<1>"
$PN"AE26"1;
"VCCP_1P8<0>"
$PN"BD46"1;
"VCCP_3P3<2>"
$PN"AD24"3;
"VCCP_3P3<1>"
$PN"BA45"3;
"VCCP_3P3<0>"
$PN"BA46"3;
"VCCP_HSIOPLL_1P05<0>"
$PN"AW48"4;
"VCCP_UPPLL_1P05<2>"
$PN"AK50"5;
"VCCRTCEXT"
$PN"AG22"19;
%"P3V3_STBY"
"1","(-1150,3025)","0","mstr_symbols","I65";
;
VOLTAGE"3.3V"
SIZE"1B"
CDS_LIB"mstr_symbols"
BODY_TYPE"PLUMBING"
HDL_POWER"P3V3_STBY";
"G\NAC"3;
%"P1V05_PCH_STBY_WM26_PLL"
"1","(-6725,3050)","0","mstr_symbols","I70";
;
VOLTAGE"1.05V"
CDS_LIB"mstr_symbols"
BOM_COST"SB"
BODY_TYPE"PLUMBING"
ROOM"SB_DECOUPLING"
HDL_POWER"P1V05_PCH_STBY_WM26_PLL";
"G\NAC"4;
%"P1V05_PCH_STBY_WM20_PLL"
"1","(-6975,3225)","0","mstr_symbols","I71";
;
VOLTAGE"1.05V"
BOM_COST"SB"
CDS_LIB"mstr_symbols"
BODY_TYPE"PLUMBING"
ROOM"SB_DECOUPLING"
HDL_POWER"P1V05_PCH_STBY_WM20_PLL";
"G\NAC"5;
%"P1V05_PCH_STBY_KR_PLL"
"1","(-7275,3350)","0","mstr_symbols","I72";
;
VOLTAGE"1.05V"
BOM_COST"SB"
CDS_LIB"mstr_symbols"
BODY_TYPE"PLUMBING"
ROOM"SB_DECOUPLING"
HDL_POWER"P1V05_PCH_STBY_KR_PLL";
"G\NAC"6;
%"P1V05_PCH_STBY_ISCLK_PLL"
"1","(-7575,3475)","0","mstr_symbols","I73";
;
VOLTAGE"1.05V"
BOM_COST"SB"
CDS_LIB"mstr_symbols"
BODY_TYPE"PLUMBING"
ROOM"SB_DECOUPLING"
HDL_POWER"P1V05_PCH_STBY_ISCLK_PLL";
"G\NAC"7;
%"P1V05_PCH_STBY_VCCA_XTAL"
"1","(-7900,3650)","0","mstr_symbols","I74";
;
VOLTAGE"1.05V"
BOM_COST"SB"
CDS_LIB"mstr_symbols"
BODY_TYPE"PLUMBING"
ROOM"SB_DECOUPLING"
HDL_POWER"P1V05_PCH_STBY_VCCA_XTAL";
"G\NAC"8;
%"P3V3_RTC_STBY"
"1","(-675,3000)","0","mstr_symbols","I75";
;
VOLTAGE"3.3V"
BOM_COST"SB"
CDS_LIB"mstr_symbols"
BODY_TYPE"PLUMBING"
ROOM"SB_DECOUPLING"
HDL_POWER"P3V3_RTC_STBY";
"G\NAC"9;
%"P1V05_PCH_STBY"
"1","(-1925,3475)","0","mstr_symbols","I76";
;
VOLTAGE"1.05V"
CDS_LIB"mstr_symbols"
BODY_TYPE"PLUMBING"
HDL_POWER"P1V05_PCH_STBY";
"G\NAC"10;
%"P1V05_PCH_STBY_VCCA_PLL0"
"1","(-6525,2925)","0","mstr_symbols","I77";
;
VOLTAGE"1.05V"
CDS_LIB"mstr_symbols"
BOM_COST"SB"
BODY_TYPE"PLUMBING"
ROOM"SB_DECOUPLING"
HDL_POWER"P1V05_PCH_STBY_VCCA_PLL0";
"G\NAC"11;
%"P1V05_PCH_STBY_VCCA_PLL1"
"1","(-6325,2800)","0","mstr_symbols","I78";
;
VOLTAGE"1.05V"
BOM_COST"SB"
CDS_LIB"mstr_symbols"
BODY_TYPE"PLUMBING"
ROOM"SB_DECOUPLING"
HDL_POWER"P1V05_PCH_STBY_VCCA_PLL1";
"G\NAC"12;
END.
